(kicad_pcb
	(version 20260206)
	(generator "pcbnew")
	(generator_version "10.0")
	(general
		(thickness 1.6)
		(legacy_teardrops no)
	)
	(paper "A4")
	(title_block
		(title "Bryce Canyon_F.DPB_16315-1-OCP.brd")
		(comment 1 "Bryce Canyon / footprint 1370 of 2223 (MONO1), pads 147-166 of 166")
	)
	(layers
		(0 "F.Cu" signal "TOP")
		(4 "In1.Cu" signal "L2GND")
		(6 "In2.Cu" signal "L3")
		(8 "In3.Cu" signal "L4GND")
		(10 "In4.Cu" signal "L5")
		(12 "In5.Cu" signal "L6VCC")
		(14 "In6.Cu" signal "L7VCC")
		(16 "In7.Cu" signal "L8")
		(18 "In8.Cu" signal "L9GND")
		(20 "In9.Cu" signal "L10")
		(22 "In10.Cu" signal "L11GND")
		(2 "B.Cu" signal "BOTTOM")
		(9 "F.Adhes" user "F.Adhesive")
		(11 "B.Adhes" user "B.Adhesive")
		(13 "F.Paste" user "Package Geometry/Pastemask Top")
		(15 "B.Paste" user "Package Geometry/Pastemask Bottom")
		(5 "F.SilkS" user "Ref Des/Silkscreen Top")
		(7 "B.SilkS" user "Ref Des/Silkscreen Bottom")
		(1 "F.Mask" user "Board Geometry/Soldermask Top")
		(3 "B.Mask" user "Board Geometry/Soldermask Bottom")
		(17 "Dwgs.User" user "User.Drawings")
		(19 "Cmts.User" user "User.Comments")
		(21 "Eco1.User" user "User.Eco1")
		(23 "Eco2.User" user "User.Eco2")
		(25 "Edge.Cuts" user "Board Geometry/Outline")
		(27 "Margin" user)
		(31 "F.CrtYd" user "Package Geometry/Place Bound Top")
		(29 "B.CrtYd" user "Package Geometry/Place Bound Bottom")
		(35 "F.Fab" user "Ref Des/Assembly Top")
		(33 "B.Fab" user "Ref Des/Assembly Bottom")
	)
	(footprint ""
		(layer "F.Cu")
		(at 239.300004 -111.149892 90)
		(property "Reference" "MONO1"
			(at 0 0 90)
			(layer "F.SilkS")
			(hide yes)
			(effects
				(font
					(size 1.27 1.27)
				)
			)
		)
		(property "Value" "AMP-CONN164-4R-1-GP"
			(at -25.705054 -1.203706 90)
			(unlocked yes)
			(layer "F.Fab")
			(hide yes)
			(effects
				(font
					(size 1.016 1.016)
					(thickness 0.1524)
				)
			)
		)
		(property "Device Type" "PREFIT-164P-890091-1H441"
			(at -25.705054 -2.727706 90)
			(unlocked yes)
			(layer "F.Fab")
			(hide yes)
			(effects
				(font
					(size 1.016 1.016)
					(thickness 0.1524)
				)
			)
		)
		(duplicate_pad_numbers_are_jumpers no)
		(pad "B63" thru_hole circle
			(at 52.349908 1.249934 90)
			(size 1.0668 1.0668)
			(drill 0.719836)
			(layers "*.Cu" "*.Mask")
			(remove_unused_layers no)
			(net "PCIE_COMP_A_TO_SCC_A_7_DP")
			(clearance 0.1905)
			(thermal_gap 0.1905)
		)
		(pad "B64" thru_hole circle
			(at 53.349906 3.24993 90)
			(size 1.0668 1.0668)
			(drill 0.719836)
			(layers "*.Cu" "*.Mask")
			(remove_unused_layers no)
			(net "PCIE_COMP_A_TO_SCC_A_7_DN")
			(clearance 0.1905)
			(thermal_gap 0.1905)
		)
		(pad "B65" thru_hole circle
			(at 54.349904 1.249934 90)
			(size 1.0668 1.0668)
			(drill 0.719836)
			(layers "*.Cu" "*.Mask")
			(remove_unused_layers no)
			(net "GND")
			(clearance 0.1905)
			(thermal_gap 0.1905)
		)
		(pad "B66" thru_hole circle
			(at 55.349902 3.24993 90)
			(size 1.0668 1.0668)
			(drill 0.719836)
			(layers "*.Cu" "*.Mask")
			(remove_unused_layers no)
			(net "GND")
			(clearance 0.1905)
			(thermal_gap 0.1905)
		)
		(pad "B67" thru_hole circle
			(at 56.3499 1.249934 90)
			(size 1.0668 1.0668)
			(drill 0.719836)
			(layers "*.Cu" "*.Mask")
			(remove_unused_layers no)
			(net "PCIE_COMP_A_TO_IOM_A_8_DP")
			(clearance 0.1905)
			(thermal_gap 0.1905)
		)
		(pad "B68" thru_hole circle
			(at 57.349898 3.24993 90)
			(size 1.0668 1.0668)
			(drill 0.719836)
			(layers "*.Cu" "*.Mask")
			(remove_unused_layers no)
			(net "PCIE_COMP_A_TO_IOM_A_8_DN")
			(clearance 0.1905)
			(thermal_gap 0.1905)
		)
		(pad "B69" thru_hole circle
			(at 58.349896 1.249934 90)
			(size 1.0668 1.0668)
			(drill 0.719836)
			(layers "*.Cu" "*.Mask")
			(remove_unused_layers no)
			(net "GND")
			(clearance 0.1905)
			(thermal_gap 0.1905)
		)
		(pad "B70" thru_hole circle
			(at 59.349894 3.24993 90)
			(size 1.0668 1.0668)
			(drill 0.719836)
			(layers "*.Cu" "*.Mask")
			(remove_unused_layers no)
			(net "GND")
			(clearance 0.1905)
			(thermal_gap 0.1905)
		)
		(pad "B71" thru_hole circle
			(at 60.349892 1.249934 90)
			(size 1.0668 1.0668)
			(drill 0.719836)
			(layers "*.Cu" "*.Mask")
			(remove_unused_layers no)
			(net "PCIE_COMP_A_TO_IOM_A_9_DP")
			(clearance 0.1905)
			(thermal_gap 0.1905)
		)
		(pad "B72" thru_hole circle
			(at 61.34989 3.24993 90)
			(size 1.0668 1.0668)
			(drill 0.719836)
			(layers "*.Cu" "*.Mask")
			(remove_unused_layers no)
			(net "PCIE_COMP_A_TO_IOM_A_9_DN")
			(clearance 0.1905)
			(thermal_gap 0.1905)
		)
		(pad "B73" thru_hole circle
			(at 62.349888 1.249934 90)
			(size 1.0668 1.0668)
			(drill 0.719836)
			(layers "*.Cu" "*.Mask")
			(remove_unused_layers no)
			(net "GND")
			(clearance 0.1905)
			(thermal_gap 0.1905)
		)
		(pad "B74" thru_hole circle
			(at 63.349886 3.24993 90)
			(size 1.0668 1.0668)
			(drill 0.719836)
			(layers "*.Cu" "*.Mask")
			(remove_unused_layers no)
			(net "GND")
			(clearance 0.1905)
			(thermal_gap 0.1905)
		)
		(pad "B75" thru_hole circle
			(at 64.349884 1.249934 90)
			(size 1.0668 1.0668)
			(drill 0.719836)
			(layers "*.Cu" "*.Mask")
			(remove_unused_layers no)
			(net "PCIE_COMP_A_TO_IOM_A_10_DP")
			(clearance 0.1905)
			(thermal_gap 0.1905)
		)
		(pad "B76" thru_hole circle
			(at 65.349882 3.24993 90)
			(size 1.0668 1.0668)
			(drill 0.719836)
			(layers "*.Cu" "*.Mask")
			(remove_unused_layers no)
			(net "PCIE_COMP_A_TO_IOM_A_10_DN")
			(clearance 0.1905)
			(thermal_gap 0.1905)
		)
		(pad "B77" thru_hole circle
			(at 66.34988 1.249934 90)
			(size 1.0668 1.0668)
			(drill 0.719836)
			(layers "*.Cu" "*.Mask")
			(remove_unused_layers no)
			(net "GND")
			(clearance 0.1905)
			(thermal_gap 0.1905)
		)
		(pad "B78" thru_hole circle
			(at 67.349878 3.24993 90)
			(size 1.0668 1.0668)
			(drill 0.719836)
			(layers "*.Cu" "*.Mask")
			(remove_unused_layers no)
			(net "GND")
			(clearance 0.1905)
			(thermal_gap 0.1905)
		)
		(pad "B79" thru_hole circle
			(at 68.349876 1.249934 90)
			(size 1.0668 1.0668)
			(drill 0.719836)
			(layers "*.Cu" "*.Mask")
			(remove_unused_layers no)
			(net "PCIE_COMP_A_TO_IOM_A_11_DP")
			(clearance 0.1905)
			(thermal_gap 0.1905)
		)
		(pad "B80" thru_hole circle
			(at 69.349874 3.24993 90)
			(size 1.0668 1.0668)
			(drill 0.719836)
			(layers "*.Cu" "*.Mask")
			(remove_unused_layers no)
			(net "PCIE_COMP_A_TO_IOM_A_11_DN")
			(clearance 0.1905)
			(thermal_gap 0.1905)
		)
		(pad "B81" thru_hole circle
			(at 70.350126 1.249934 90)
			(size 1.0668 1.0668)
			(drill 0.719836)
			(layers "*.Cu" "*.Mask")
			(remove_unused_layers no)
			(net "GND")
			(clearance 0.1905)
			(thermal_gap 0.1905)
		)
		(pad "B82" thru_hole circle
			(at 71.350124 3.24993 90)
			(size 1.0668 1.0668)
			(drill 0.719836)
			(layers "*.Cu" "*.Mask")
			(remove_unused_layers no)
			(net "GND")
			(clearance 0.1905)
			(thermal_gap 0.1905)
		)
	)
)
